(kicad_pcb
	(version 20211014)
	(generator pcbnew)
	(general
    (thickness 1.6)
  )
	(paper "A4")
	(title_block
    (title "SA800U (Snapdragon 845) Baseboard")
    (date "2023-10-19")
    (rev "1.0.3")
    (company "Antmicro Ltd.")
    (comment 1 "www.antmicro.com")
		(comment 9 "footprints 358-362 of 589")
	)
	(layers
    (0 "F.Cu" signal)
    (1 "In1.Cu" power)
    (2 "In2.Cu" signal)
    (3 "In3.Cu" signal)
    (4 "In4.Cu" power)
    (31 "B.Cu" signal)
    (32 "B.Adhes" user "B.Adhesive")
    (33 "F.Adhes" user "F.Adhesive")
    (34 "B.Paste" user)
    (35 "F.Paste" user)
    (36 "B.SilkS" user "B.Silkscreen")
    (37 "F.SilkS" user "F.Silkscreen")
    (38 "B.Mask" user)
    (39 "F.Mask" user)
    (40 "Dwgs.User" user "User.Drawings")
    (41 "Cmts.User" user "User.Comments")
    (42 "Eco1.User" user "User.Eco1")
    (43 "Eco2.User" user "User.Eco2")
    (44 "Edge.Cuts" user)
    (45 "Margin" user)
    (46 "B.CrtYd" user "B.Courtyard")
    (47 "F.CrtYd" user "F.Courtyard")
    (48 "B.Fab" user)
    (49 "F.Fab" user)
  )
	(footprint "sa800u-baseboard-hw-footprints:QFN-32-1EP_4x4mm_P0.4mm" (layer "B.Cu")
    (tedit 619D0372)
    (at 97.171211 103.09844)
    (property "Author" "Antmicro")
    (property "License" "Apache-2.0")
    (property "MPN" "RTL8111H")
    (property "Manufacturer" "Realtek")
    (property "Sheetfile" "ethernet-controller.kicad_sch")
    (property "Sheetname" "Ethernet Controller")
    (attr smd)
    (fp_text reference "U1" (at 3.248789 -2.36844 180) (layer "B.SilkS")
      (effects (font (size 0.7 0.7) (thickness 0.15)) (justify left bottom mirror))
    )
    (fp_text value "RTL8111H" (at 0 -3.5 180) (layer "B.Fab")
      (effects (font (size 0.7 0.7) (thickness 0.15)) (justify left bottom mirror))
    )
    (fp_text user "Author: Antmicro" (at -2.851 -7.888 180) (layer "B.Fab") hide
      (effects (font (size 0.7 0.7) (thickness 0.15)) (justify left bottom mirror))
    )
    (fp_text user "${REFERENCE}" (at -2.851 -6.688 180) (layer "B.Fab") hide
      (effects (font (size 0.7 0.7) (thickness 0.15)) (justify left bottom mirror))
    )
    (fp_text user "License: Apache-2.0" (at -2.851 -9.088 180) (layer "B.Fab") hide
      (effects (font (size 0.7 0.7) (thickness 0.15)) (justify left bottom mirror))
    )
    (fp_poly (pts
        (xy -0.919 0.918)
        (xy 0.917 0.918)
        (xy 0.917 -0.918)
        (xy -0.919 -0.918)
      ) (layer "B.Paste") (width 0.01) (fill solid))
    (fp_line (start -1.69 2) (end -2 2) (layer "B.SilkS") (width 0.15))
    (fp_line (start 1.999 2) (end 1.689 2) (layer "B.SilkS") (width 0.15))
    (fp_line (start -2 2) (end -2 1.69) (layer "B.SilkS") (width 0.15))
    (fp_line (start -2 -1.689) (end -2 -1.999) (layer "B.SilkS") (width 0.15))
    (fp_line (start 1.999 -1.999) (end 1.999 -1.689) (layer "B.SilkS") (width 0.15))
    (fp_line (start 1.999 1.69) (end 1.999 2) (layer "B.SilkS") (width 0.15))
    (fp_line (start 1.689 -1.999) (end 1.999 -1.999) (layer "B.SilkS") (width 0.15))
    (fp_line (start -2 -1.999) (end -1.69 -1.999) (layer "B.SilkS") (width 0.15))
    (fp_circle (center -2.3 1.7) (end -2.25 1.7) (layer "B.SilkS") (width 0.15) (fill solid))
    (fp_line (start 2.24 -1.75) (end 2.24 -2.24) (layer "B.CrtYd") (width 0.05))
    (fp_line (start -1.76 -2.24) (end -2.25 -2.24) (layer "B.CrtYd") (width 0.05))
    (fp_line (start -2.25 -2.24) (end -2.25 -1.75) (layer "B.CrtYd") (width 0.05))
    (fp_line (start 1.75 2.61) (end 1.75 2.25) (layer "B.CrtYd") (width 0.05))
    (fp_line (start 1.75 -2.24) (end 1.75 -2.6) (layer "B.CrtYd") (width 0.05))
    (fp_line (start -1.76 2.61) (end 1.75 2.61) (layer "B.CrtYd") (width 0.05))
    (fp_line (start -2.25 2.25) (end -1.76 2.25) (layer "B.CrtYd") (width 0.05))
    (fp_line (start 2.24 -2.24) (end 1.75 -2.24) (layer "B.CrtYd") (width 0.05))
    (fp_line (start 1.75 -2.6) (end -1.76 -2.6) (layer "B.CrtYd") (width 0.05))
    (fp_line (start 1.75 2.25) (end 2.24 2.25) (layer "B.CrtYd") (width 0.05))
    (fp_line (start -1.76 2.25) (end -1.76 2.61) (layer "B.CrtYd") (width 0.05))
    (fp_line (start 2.24 2.25) (end 2.24 1.76) (layer "B.CrtYd") (width 0.05))
    (fp_line (start -2.61 1.76) (end -2.25 1.76) (layer "B.CrtYd") (width 0.05))
    (fp_line (start 2.24 1.76) (end 2.6 1.76) (layer "B.CrtYd") (width 0.05))
    (fp_line (start 2.6 -1.75) (end 2.24 -1.75) (layer "B.CrtYd") (width 0.05))
    (fp_line (start 2.6 1.76) (end 2.6 -1.75) (layer "B.CrtYd") (width 0.05))
    (fp_line (start -1.76 -2.6) (end -1.76 -2.24) (layer "B.CrtYd") (width 0.05))
    (fp_line (start -2.25 -1.75) (end -2.61 -1.75) (layer "B.CrtYd") (width 0.05))
    (fp_line (start -2.61 -1.75) (end -2.61 1.76) (layer "B.CrtYd") (width 0.05))
    (fp_line (start -2.25 1.76) (end -2.25 2.25) (layer "B.CrtYd") (width 0.05))
    (fp_line (start 1.999 -1.999) (end -2 -1.999) (layer "B.Fab") (width 0.15))
    (fp_line (start -2 2) (end 1.999 2) (layer "B.Fab") (width 0.15))
    (fp_line (start -2 -1.999) (end -2 2) (layer "B.Fab") (width 0.15))
    (fp_line (start 1.999 2) (end 1.999 -1.999) (layer "B.Fab") (width 0.15))
    (fp_circle (center -1.45 1.371) (end -1.351 1.371) (layer "B.Fab") (width 0.15) (fill none))
    (pad "1" smd roundrect (at -2.005 1.4) (size 0.71 0.22) (layers "B.Cu" "B.Paste" "B.Mask") (roundrect_rratio 0.03)
      (net 255 "/Ethernet Controller/LAN0_MDI0_P") (pinfunction "MDIP0") (pintype "bidirectional"))
    (pad "2" smd roundrect (at -2.005 1) (size 0.71 0.22) (layers "B.Cu" "B.Paste" "B.Mask") (roundrect_rratio 0.03)
      (net 254 "/Ethernet Controller/LAN0_MDI0_N") (pinfunction "MDIN0") (pintype "bidirectional"))
    (pad "3" smd roundrect (at -2.005 0.6) (size 0.71 0.22) (layers "B.Cu" "B.Paste" "B.Mask") (roundrect_rratio 0.03)
      (net 181 "/Ethernet Controller/ETH_1V0") (pinfunction "AVDD10") (pintype "power_in"))
    (pad "4" smd roundrect (at -2.005 0.201) (size 0.71 0.22) (layers "B.Cu" "B.Paste" "B.Mask") (roundrect_rratio 0.03)
      (net 257 "/Ethernet Controller/LAN0_MDI1_P") (pinfunction "MDIP1") (pintype "bidirectional"))
    (pad "5" smd roundrect (at -2.005 -0.2) (size 0.71 0.22) (layers "B.Cu" "B.Paste" "B.Mask") (roundrect_rratio 0.03)
      (net 256 "/Ethernet Controller/LAN0_MDI1_N") (pinfunction "MDIN1") (pintype "bidirectional"))
    (pad "6" smd roundrect (at -2.005 -0.599) (size 0.71 0.22) (layers "B.Cu" "B.Paste" "B.Mask") (roundrect_rratio 0.03)
      (net 259 "/Ethernet Controller/LAN0_MDI2_P") (pinfunction "MDIP2") (pintype "bidirectional"))
    (pad "7" smd roundrect (at -2.005 -0.999) (size 0.71 0.22) (layers "B.Cu" "B.Paste" "B.Mask") (roundrect_rratio 0.03)
      (net 258 "/Ethernet Controller/LAN0_MDI2_N") (pinfunction "MDIN2") (pintype "bidirectional"))
    (pad "8" smd roundrect (at -2.005 -1.399) (size 0.71 0.22) (layers "B.Cu" "B.Paste" "B.Mask") (roundrect_rratio 0.03)
      (net 181 "/Ethernet Controller/ETH_1V0") (pinfunction "AVDD10_1") (pintype "power_in"))
    (pad "9" smd roundrect (at -1.4 -2.004) (size 0.22 0.71) (layers "B.Cu" "B.Paste" "B.Mask") (roundrect_rratio 0.03)
      (net 261 "/Ethernet Controller/LAN0_MDI3_P") (pinfunction "MDIP3") (pintype "bidirectional"))
    (pad "10" smd roundrect (at -1 -2.004) (size 0.22 0.71) (layers "B.Cu" "B.Paste" "B.Mask") (roundrect_rratio 0.03)
      (net 260 "/Ethernet Controller/LAN0_MDI3_N") (pinfunction "MDIN3") (pintype "bidirectional"))
    (pad "11" smd roundrect (at -0.6 -2.004) (size 0.22 0.71) (layers "B.Cu" "B.Paste" "B.Mask") (roundrect_rratio 0.03)
      (net 177 "/Ethernet Controller/ETH_3V3") (pinfunction "AVDD33_1") (pintype "power_in"))
    (pad "12" smd roundrect (at -0.201 -2.004) (size 0.22 0.71) (layers "B.Cu" "B.Paste" "B.Mask") (roundrect_rratio 0.03)
      (net 162 "PCIE1_CLKREQ_N") (pinfunction "CLKREQB") (pintype "open_collector"))
    (pad "13" smd roundrect (at 0.2 -2.004) (size 0.22 0.71) (layers "B.Cu" "B.Paste" "B.Mask") (roundrect_rratio 0.03)
      (net 49 "PCIE1_TX_P") (pinfunction "HSIP") (pintype "input"))
    (pad "14" smd roundrect (at 0.599 -2.004) (size 0.22 0.71) (layers "B.Cu" "B.Paste" "B.Mask") (roundrect_rratio 0.03)
      (net 48 "PCIE1_TX_N") (pinfunction "HSIN") (pintype "input"))
    (pad "15" smd roundrect (at 0.999 -2.004) (size 0.22 0.71) (layers "B.Cu" "B.Paste" "B.Mask") (roundrect_rratio 0.03)
      (net 47 "PCIE1_REFCLK_P") (pinfunction "REFCLK_P") (pintype "input"))
    (pad "16" smd roundrect (at 1.399 -2.004) (size 0.22 0.71) (layers "B.Cu" "B.Paste" "B.Mask") (roundrect_rratio 0.03)
      (net 46 "PCIE1_REFCLK_N") (pinfunction "REFCLK_N") (pintype "input"))
    (pad "17" smd roundrect (at 2.004 -1.399) (size 0.71 0.22) (layers "B.Cu" "B.Paste" "B.Mask") (roundrect_rratio 0.03)
      (net 179 "/Ethernet Controller/PCIE1_RX_C_P") (pinfunction "HSOP") (pintype "output"))
    (pad "18" smd roundrect (at 2.004 -0.999) (size 0.71 0.22) (layers "B.Cu" "B.Paste" "B.Mask") (roundrect_rratio 0.03)
      (net 180 "/Ethernet Controller/PCIE1_RX_C_N") (pinfunction "HSON") (pintype "output"))
    (pad "19" smd roundrect (at 2.004 -0.599) (size 0.71 0.22) (layers "B.Cu" "B.Paste" "B.Mask") (roundrect_rratio 0.03)
      (net 163 "PCIE1_RST_N") (pinfunction "PERSTB") (pintype "input"))
    (pad "20" smd roundrect (at 2.004 -0.2) (size 0.71 0.22) (layers "B.Cu" "B.Paste" "B.Mask") (roundrect_rratio 0.03)
      (net 286 "/Ethernet Controller/ETH_ISOLATEB") (pinfunction "ISOLATEB") (pintype "open_collector"))
    (pad "21" smd roundrect (at 2.004 0.201) (size 0.71 0.22) (layers "B.Cu" "B.Paste" "B.Mask") (roundrect_rratio 0.03)
      (net 161 "PCIE1_WAKE_N") (pinfunction "LANWAKEB") (pintype "output"))
    (pad "22" smd roundrect (at 2.004 0.6) (size 0.71 0.22) (layers "B.Cu" "B.Paste" "B.Mask") (roundrect_rratio 0.03)
      (net 181 "/Ethernet Controller/ETH_1V0") (pinfunction "DVDD10") (pintype "power_in"))
    (pad "23" smd roundrect (at 2.004 1) (size 0.71 0.22) (layers "B.Cu" "B.Paste" "B.Mask") (roundrect_rratio 0.03)
      (net 177 "/Ethernet Controller/ETH_3V3") (pinfunction "VDDREG") (pintype "power_in"))
    (pad "24" smd roundrect (at 2.004 1.4) (size 0.71 0.22) (layers "B.Cu" "B.Paste" "B.Mask") (roundrect_rratio 0.03)
      (net 178 "/Ethernet Controller/REG_1V0") (pinfunction "REGOUT") (pintype "output"))
    (pad "25" smd roundrect (at 1.399 2.005) (size 0.22 0.71) (layers "B.Cu" "B.Paste" "B.Mask") (roundrect_rratio 0.03)
      (net 263 "/Ethernet Controller/ETH_LED2") (pinfunction "LED2") (pintype "output"))
    (pad "26" smd roundrect (at 0.999 2.005) (size 0.22 0.71) (layers "B.Cu" "B.Paste" "B.Mask") (roundrect_rratio 0.03)
      (net 469 "unconnected-(U1-Pad26)") (pinfunction "LED1/GPO") (pintype "output+no_connect"))
    (pad "27" smd roundrect (at 0.599 2.005) (size 0.22 0.71) (layers "B.Cu" "B.Paste" "B.Mask") (roundrect_rratio 0.03)
      (net 262 "/Ethernet Controller/ETH_LED0") (pinfunction "LED0") (pintype "output"))
    (pad "28" smd roundrect (at 0.2 2.005) (size 0.22 0.71) (layers "B.Cu" "B.Paste" "B.Mask") (roundrect_rratio 0.03)
      (net 182 "/Ethernet Controller/XTAL1") (pinfunction "CKXTAL1") (pintype "input"))
    (pad "29" smd roundrect (at -0.201 2.005) (size 0.22 0.71) (layers "B.Cu" "B.Paste" "B.Mask") (roundrect_rratio 0.03)
      (net 183 "/Ethernet Controller/XTAL2") (pinfunction "CKXTAL2") (pintype "input"))
    (pad "30" smd roundrect (at -0.6 2.005) (size 0.22 0.71) (layers "B.Cu" "B.Paste" "B.Mask") (roundrect_rratio 0.03)
      (net 181 "/Ethernet Controller/ETH_1V0") (pinfunction "AVD10_2") (pintype "power_in"))
    (pad "31" smd roundrect (at -1 2.005) (size 0.22 0.71) (layers "B.Cu" "B.Paste" "B.Mask") (roundrect_rratio 0.03)
      (net 393 "Net-(R11-Pad1)") (pinfunction "RSET") (pintype "input"))
    (pad "32" smd roundrect (at -1.4 2.005) (size 0.22 0.71) (layers "B.Cu" "B.Paste" "B.Mask") (roundrect_rratio 0.03)
      (net 177 "/Ethernet Controller/ETH_3V3") (pinfunction "AVDD33_2") (pintype "input"))
    (pad "33" smd rect (at 0 0) (size 2.8 2.8) (layers "B.Cu" "B.Mask")
      (net 1 "GND") (pinfunction "GND") (pintype "power_in"))
  )
	(footprint "sa800u-baseboard-hw-footprints:R_0402_1005Metric" (layer "B.Cu")
    (tedit 5FD9C158)
    (at 101.549173 102.257734 180)
    (descr "Resistor SMD 0402")
    (tags "resistor SMD 0402")
    (property "Author" "Antmicro")
    (property "License" "Apache-2.0")
    (property "MPN" "CR0402-FX-1001GLF")
    (property "Manufacturer" "Bourns")
    (property "Sheetfile" "ethernet-controller.kicad_sch")
    (property "Sheetname" "Ethernet Controller")
    (property "Tolerance" "1%")
    (property "Val" "1k")
    (attr smd)
    (fp_text reference "R9" (at -2.420827 -0.272266) (layer "B.SilkS")
      (effects (font (size 0.7 0.7) (thickness 0.15)) (justify left bottom mirror))
    )
    (fp_text value "R_1k_0402" (at 0 -1.4) (layer "B.Fab")
      (effects (font (size 0.7 0.7) (thickness 0.15)) (justify left bottom mirror))
    )
    (fp_text user "License: Apache-2.0" (at -0.95 -5.169) (layer "B.Fab") hide
      (effects (font (size 0.7 0.7) (thickness 0.15)) (justify left bottom mirror))
    )
    (fp_text user "Author: Antmicro" (at -0.95 -4.169) (layer "B.Fab") hide
      (effects (font (size 0.7 0.7) (thickness 0.15)) (justify left bottom mirror))
    )
    (fp_text user "${REFERENCE}" (at -0.95 -3.168) (layer "B.Fab") hide
      (effects (font (size 0.7 0.7) (thickness 0.15)) (justify left bottom mirror))
    )
    (fp_rect (start -0.93 0.47) (end 0.93 -0.47) (layer "B.CrtYd") (width 0.05) (fill none))
    (fp_rect (start -0.5 0.25) (end 0.5 -0.25) (layer "B.Fab") (width 0.15) (fill none))
    (pad "1" smd roundrect (at -0.485 0 180) (size 0.59 0.64) (layers "B.Cu" "B.Paste" "B.Mask") (roundrect_rratio 0.25)
      (net 131 "3V3_SYS") (pintype "passive"))
    (pad "2" smd roundrect (at 0.485 0 180) (size 0.59 0.64) (layers "B.Cu" "B.Paste" "B.Mask") (roundrect_rratio 0.25)
      (net 286 "/Ethernet Controller/ETH_ISOLATEB") (pintype "passive"))
  )
	(footprint "sa800u-baseboard-hw-footprints:R_0402_1005Metric" (layer "B.Cu")
    (tedit 5FD9C158)
    (at 101.549173 101.257734 180)
    (descr "Resistor SMD 0402")
    (tags "resistor SMD 0402")
    (property "Author" "Antmicro")
    (property "License" "Apache-2.0")
    (property "MPN" "CR0402-FX-1002GLF")
    (property "Manufacturer" "Bourns")
    (property "Sheetfile" "ethernet-controller.kicad_sch")
    (property "Sheetname" "Ethernet Controller")
    (property "Tolerance" "1%")
    (property "Val" "10k")
    (attr smd)
    (fp_text reference "R8" (at -2.350827 -0.332266) (layer "B.SilkS")
      (effects (font (size 0.7 0.7) (thickness 0.15)) (justify left bottom mirror))
    )
    (fp_text value "R_10k_0402" (at 0 -1.4) (layer "B.Fab")
      (effects (font (size 0.7 0.7) (thickness 0.15)) (justify left bottom mirror))
    )
    (fp_text user "Author: Antmicro" (at -0.95 -4.169) (layer "B.Fab") hide
      (effects (font (size 0.7 0.7) (thickness 0.15)) (justify left bottom mirror))
    )
    (fp_text user "License: Apache-2.0" (at -0.95 -5.169) (layer "B.Fab") hide
      (effects (font (size 0.7 0.7) (thickness 0.15)) (justify left bottom mirror))
    )
    (fp_text user "${REFERENCE}" (at -0.95 -3.168) (layer "B.Fab") hide
      (effects (font (size 0.7 0.7) (thickness 0.15)) (justify left bottom mirror))
    )
    (fp_rect (start -0.93 0.47) (end 0.93 -0.47) (layer "B.CrtYd") (width 0.05) (fill none))
    (fp_rect (start -0.5 0.25) (end 0.5 -0.25) (layer "B.Fab") (width 0.15) (fill none))
    (pad "1" smd roundrect (at -0.485 0 180) (size 0.59 0.64) (layers "B.Cu" "B.Paste" "B.Mask") (roundrect_rratio 0.25)
      (net 132 "VREG_S4A_1V8") (pintype "passive"))
    (pad "2" smd roundrect (at 0.485 0 180) (size 0.59 0.64) (layers "B.Cu" "B.Paste" "B.Mask") (roundrect_rratio 0.25)
      (net 163 "PCIE1_RST_N") (pintype "passive"))
  )
	(footprint "sa800u-baseboard-hw-footprints:R_0402_1005Metric" (layer "B.Cu")
    (tedit 5FD9C158)
    (at 96.8 98 -90)
    (descr "Resistor SMD 0402")
    (tags "resistor SMD 0402")
    (property "Author" "Antmicro")
    (property "License" "Apache-2.0")
    (property "MPN" "CR0402-FX-1002GLF")
    (property "Manufacturer" "Bourns")
    (property "Sheetfile" "ethernet-controller.kicad_sch")
    (property "Sheetname" "Ethernet Controller")
    (property "Tolerance" "1%")
    (property "Val" "10k")
    (attr smd)
    (fp_text reference "R6" (at -0.78 -1.36 90) (layer "B.SilkS")
      (effects (font (size 0.7 0.7) (thickness 0.15)) (justify left bottom mirror))
    )
    (fp_text value "R_10k_0402" (at 0 -1.4 90) (layer "B.Fab")
      (effects (font (size 0.7 0.7) (thickness 0.15)) (justify left bottom mirror))
    )
    (fp_text user "Author: Antmicro" (at -0.95 -4.169 90) (layer "B.Fab") hide
      (effects (font (size 0.7 0.7) (thickness 0.15)) (justify left bottom mirror))
    )
    (fp_text user "License: Apache-2.0" (at -0.95 -5.169 90) (layer "B.Fab") hide
      (effects (font (size 0.7 0.7) (thickness 0.15)) (justify left bottom mirror))
    )
    (fp_text user "${REFERENCE}" (at -0.95 -3.168 90) (layer "B.Fab") hide
      (effects (font (size 0.7 0.7) (thickness 0.15)) (justify left bottom mirror))
    )
    (fp_rect (start -0.93 0.47) (end 0.93 -0.47) (layer "B.CrtYd") (width 0.05) (fill none))
    (fp_rect (start -0.5 0.25) (end 0.5 -0.25) (layer "B.Fab") (width 0.15) (fill none))
    (pad "1" smd roundrect (at -0.485 0 270) (size 0.59 0.64) (layers "B.Cu" "B.Paste" "B.Mask") (roundrect_rratio 0.25)
      (net 132 "VREG_S4A_1V8") (pintype "passive"))
    (pad "2" smd roundrect (at 0.485 0 270) (size 0.59 0.64) (layers "B.Cu" "B.Paste" "B.Mask") (roundrect_rratio 0.25)
      (net 162 "PCIE1_CLKREQ_N") (pintype "passive"))
  )
	(footprint "sa800u-baseboard-hw-footprints:R_0402_1005Metric" (layer "B.Cu")
    (tedit 5FD9C158)
    (at 93.749174 106.957733 -90)
    (descr "Resistor SMD 0402")
    (tags "resistor SMD 0402")
    (property "Author" "Antmicro")
    (property "License" "Apache-2.0")
    (property "MPN" "CR0402-FX-2491GLF")
    (property "Manufacturer" "Bourns")
    (property "Sheetfile" "ethernet-controller.kicad_sch")
    (property "Sheetname" "Ethernet Controller")
    (property "Tolerance" "1%")
    (property "Val" "2k49")
    (attr smd)
    (fp_text reference "R11" (at 0 0.7 90) (layer "B.SilkS")
      (effects (font (size 0.7 0.7) (thickness 0.15)) (justify left bottom mirror))
    )
    (fp_text value "R_2k49_0402" (at 0 -1.4 90) (layer "B.Fab")
      (effects (font (size 0.7 0.7) (thickness 0.15)) (justify left bottom mirror))
    )
    (fp_text user "License: Apache-2.0" (at -0.95 -5.169 90) (layer "B.Fab") hide
      (effects (font (size 0.7 0.7) (thickness 0.15)) (justify left bottom mirror))
    )
    (fp_text user "${REFERENCE}" (at -0.95 -3.168 90) (layer "B.Fab") hide
      (effects (font (size 0.7 0.7) (thickness 0.15)) (justify left bottom mirror))
    )
    (fp_text user "Author: Antmicro" (at -0.95 -4.169 90) (layer "B.Fab") hide
      (effects (font (size 0.7 0.7) (thickness 0.15)) (justify left bottom mirror))
    )
    (fp_rect (start -0.93 0.47) (end 0.93 -0.47) (layer "B.CrtYd") (width 0.05) (fill none))
    (fp_rect (start -0.5 0.25) (end 0.5 -0.25) (layer "B.Fab") (width 0.15) (fill none))
    (pad "1" smd roundrect (at -0.485 0 270) (size 0.59 0.64) (layers "B.Cu" "B.Paste" "B.Mask") (roundrect_rratio 0.25)
      (net 393 "Net-(R11-Pad1)") (pintype "passive"))
    (pad "2" smd roundrect (at 0.485 0 270) (size 0.59 0.64) (layers "B.Cu" "B.Paste" "B.Mask") (roundrect_rratio 0.25)
      (net 1 "GND") (pintype "passive"))
  )
)
